FILE_TYPE = CONNECTIVITY;
{Allegro Design Entry HDL 17.2-2016 S081 (4005846) 1/11/2022}
"PAGE_NUMBER" = 59;
0"NC";
1"TP_DMI_CPU1_PCH_TX_DP<7:0>";
2"TP_DMI_CPU1_PCH_TX_DN<7:0>";
3"TP_DMI_CPU1_PCH_RX_C_DP<7:0>";
4"TP_DMI_CPU1_PCH_RX_C_DN<7:0>";
5"TP_DMI_CPU1_PCH_RX_C_DN<7>";
6"TP_DMI_CPU1_PCH_RX_C_DN<6>";
7"TP_DMI_CPU1_PCH_RX_C_DN<5>";
8"TP_DMI_CPU1_PCH_RX_C_DN<4>";
9"TP_DMI_CPU1_PCH_RX_C_DN<3>";
10"TP_DMI_CPU1_PCH_RX_C_DN<2>";
11"TP_DMI_CPU1_PCH_RX_C_DN<1>";
12"TP_DMI_CPU1_PCH_RX_C_DN<0>";
13"TP_DMI_CPU1_PCH_RX_C_DP<7>";
14"TP_DMI_CPU1_PCH_RX_C_DP<6>";
15"TP_DMI_CPU1_PCH_RX_C_DP<5>";
16"TP_DMI_CPU1_PCH_RX_C_DP<4>";
17"TP_DMI_CPU1_PCH_RX_C_DP<3>";
18"TP_DMI_CPU1_PCH_RX_C_DP<2>";
19"TP_DMI_CPU1_PCH_RX_C_DP<1>";
20"TP_DMI_CPU1_PCH_RX_C_DP<0>";
21"TP_DMI_CPU1_PCH_TX_DN<7>";
22"TP_DMI_CPU1_PCH_TX_DN<6>";
23"TP_DMI_CPU1_PCH_TX_DN<5>";
24"TP_DMI_CPU1_PCH_TX_DN<4>";
25"TP_DMI_CPU1_PCH_TX_DN<3>";
26"TP_DMI_CPU1_PCH_TX_DN<2>";
27"TP_DMI_CPU1_PCH_TX_DN<1>";
28"TP_DMI_CPU1_PCH_TX_DN<0>";
29"TP_DMI_CPU1_PCH_TX_DP<7>";
30"TP_DMI_CPU1_PCH_TX_DP<6>";
31"TP_DMI_CPU1_PCH_TX_DP<5>";
32"TP_DMI_CPU1_PCH_TX_DP<4>";
33"TP_DMI_CPU1_PCH_TX_DP<3>";
34"TP_DMI_CPU1_PCH_TX_DP<2>";
35"TP_DMI_CPU1_PCH_TX_DP<1>";
36"TP_DMI_CPU1_PCH_TX_DP<0>";
%"TAP"
"1","(-725,3325)","2","standard","I10";
;
CDS_LIB"standard"
BODY_TYPE"PLUMBING"
HDL_TAP"TRUE";
"B \NAC \NWC"4;
"S \NAC"
BN"6"6;
%"TAP"
"1","(-725,3275)","2","standard","I11";
;
CDS_LIB"standard"
BODY_TYPE"PLUMBING"
HDL_TAP"TRUE";
"B \NAC \NWC"4;
"S \NAC"
BN"5"7;
%"TAP"
"1","(-725,3625)","2","standard","I12";
;
CDS_LIB"standard"
BODY_TYPE"PLUMBING"
HDL_TAP"TRUE";
"B \NAC \NWC"3;
"S \NAC"
BN"3"17;
%"TAP"
"1","(-725,3575)","2","standard","I13";
;
CDS_LIB"standard"
BODY_TYPE"PLUMBING"
HDL_TAP"TRUE";
"B \NAC \NWC"3;
"S \NAC"
BN"2"18;
%"TAP"
"1","(-725,3475)","2","standard","I14";
;
CDS_LIB"standard"
BODY_TYPE"PLUMBING"
HDL_TAP"TRUE";
"B \NAC \NWC"3;
"S \NAC"
BN"0"20;
%"TAP"
"1","(-725,3525)","2","standard","I15";
;
CDS_LIB"standard"
BODY_TYPE"PLUMBING"
HDL_TAP"TRUE";
"B \NAC \NWC"3;
"S \NAC"
BN"1"19;
%"TAP"
"1","(-725,3825)","2","standard","I16";
;
CDS_LIB"standard"
BODY_TYPE"PLUMBING"
HDL_TAP"TRUE";
"B \NAC \NWC"3;
"S \NAC"
BN"7"13;
%"TAP"
"1","(-725,3775)","2","standard","I17";
;
CDS_LIB"standard"
BODY_TYPE"PLUMBING"
HDL_TAP"TRUE";
"B \NAC \NWC"3;
"S \NAC"
BN"6"14;
%"TAP"
"1","(-725,3675)","2","standard","I18";
;
CDS_LIB"standard"
BODY_TYPE"PLUMBING"
HDL_TAP"TRUE";
"B \NAC \NWC"3;
"S \NAC"
BN"4"16;
%"TAP"
"1","(-725,3725)","2","standard","I19";
;
CDS_LIB"standard"
BODY_TYPE"PLUMBING"
HDL_TAP"TRUE";
"B \NAC \NWC"3;
"S \NAC"
BN"5"15;
%"SOCKET4677_AZIF0045P001C01CS"
"16","(975,3425)","0","pure_quanta","I20";
;
PART_NUMBER"DGA^7000023"
VALUE"SOCKET4677_AZIF0045-P001C01CS"
MATERIAL"IO"
PART_TYPE"SMLF"
$LOCATION"U1"
CDS_LMAN_SYM_OUTLINE"-1050,550,1050,-550"
NEEDS_NO_SIZE"TRUE"
CDS_LIB"pure_quanta"
CDS_LOCATION"U1"
$SEC"16"
CDS_SEC"16";
"DMI_TX_DP0"
$PN"CA19"36;
"DMI_TX_DP1"
$PN"BY18"35;
"DMI_TX_DP2"
$PN"CC19"34;
"DMI_TX_DP3"
$PN"CD18"33;
"DMI_TX_DP4"
$PN"CG19"32;
"DMI_TX_DP5"
$PN"CH18"31;
"DMI_TX_DP6"
$PN"CL19"30;
"DMI_TX_DP7"
$PN"CM18"29;
"DMI_TX_DN0"
$PN"BW19"28;
"DMI_TX_DN1"
$PN"CA17"27;
"DMI_TX_DN2"
$PN"CB18"26;
"DMI_TX_DN3"
$PN"CE17"25;
"DMI_TX_DN4"
$PN"CF18"24;
"DMI_TX_DN5"
$PN"CJ17"23;
"DMI_TX_DN6"
$PN"CK18"22;
"DMI_TX_DN7"
$PN"CN17"21;
"DMI_RX_DP0"
$PN"BC19"20;
"DMI_RX_DP1"
$PN"BD18"19;
"DMI_RX_DP2"
$PN"BG19"18;
"DMI_RX_DP3"
$PN"BH18"17;
"DMI_RX_DP4"
$PN"BL19"16;
"DMI_RX_DP5"
$PN"BM18"15;
"DMI_RX_DP6"
$PN"BR19"14;
"DMI_RX_DP7"
$PN"BT18"13;
"DMI_RX_DN0"
$PN"BB18"12;
"DMI_RX_DN1"
$PN"BE17"11;
"DMI_RX_DN2"
$PN"BF18"10;
"DMI_RX_DN3"
$PN"BJ17"9;
"DMI_RX_DN4"
$PN"BK18"8;
"DMI_RX_DN5"
$PN"BN17"7;
"DMI_RX_DN6"
$PN"BP18"6;
"DMI_RX_DN7"
$PN"BU17"5;
%"TAP"
"1","(2650,3025)","0","standard","I21";
;
CDS_LIB"standard"
BODY_TYPE"PLUMBING"
HDL_TAP"TRUE";
"B \NAC \NWC"2;
"S \NAC"
BN"0"28;
%"TAP"
"1","(2650,3125)","0","standard","I22";
;
CDS_LIB"standard"
BODY_TYPE"PLUMBING"
HDL_TAP"TRUE";
"B \NAC \NWC"2;
"S \NAC"
BN"2"26;
%"TAP"
"1","(2650,3075)","0","standard","I23";
;
CDS_LIB"standard"
BODY_TYPE"PLUMBING"
HDL_TAP"TRUE";
"B \NAC \NWC"2;
"S \NAC"
BN"1"27;
%"TAP"
"1","(2650,3175)","0","standard","I24";
;
CDS_LIB"standard"
BODY_TYPE"PLUMBING"
HDL_TAP"TRUE";
"B \NAC \NWC"2;
"S \NAC"
BN"3"25;
%"TAP"
"1","(2650,3225)","0","standard","I25";
;
CDS_LIB"standard"
BODY_TYPE"PLUMBING"
HDL_TAP"TRUE";
"B \NAC \NWC"2;
"S \NAC"
BN"4"24;
%"TAP"
"1","(2650,3275)","0","standard","I26";
;
CDS_LIB"standard"
BODY_TYPE"PLUMBING"
HDL_TAP"TRUE";
"B \NAC \NWC"2;
"S \NAC"
BN"5"23;
%"TAP"
"1","(2650,3375)","0","standard","I27";
;
CDS_LIB"standard"
BODY_TYPE"PLUMBING"
HDL_TAP"TRUE";
"B \NAC \NWC"2;
"S \NAC"
BN"7"21;
%"TAP"
"1","(2650,3325)","0","standard","I28";
;
CDS_LIB"standard"
BODY_TYPE"PLUMBING"
HDL_TAP"TRUE";
"B \NAC \NWC"2;
"S \NAC"
BN"6"22;
%"TAP"
"1","(2650,3525)","0","standard","I29";
;
CDS_LIB"standard"
BODY_TYPE"PLUMBING"
HDL_TAP"TRUE";
"B \NAC \NWC"1;
"S \NAC"
BN"1"35;
%"TAP"
"1","(2650,3475)","0","standard","I30";
;
CDS_LIB"standard"
BODY_TYPE"PLUMBING"
HDL_TAP"TRUE";
"B \NAC \NWC"1;
"S \NAC"
BN"0"36;
%"TAP"
"1","(2650,3625)","0","standard","I31";
;
CDS_LIB"standard"
BODY_TYPE"PLUMBING"
HDL_TAP"TRUE";
"B \NAC \NWC"1;
"S \NAC"
BN"3"33;
%"TAP"
"1","(2650,3575)","0","standard","I32";
;
CDS_LIB"standard"
BODY_TYPE"PLUMBING"
HDL_TAP"TRUE";
"B \NAC \NWC"1;
"S \NAC"
BN"2"34;
%"TAP"
"1","(2650,3775)","0","standard","I33";
;
CDS_LIB"standard"
BODY_TYPE"PLUMBING"
HDL_TAP"TRUE";
"B \NAC \NWC"1;
"S \NAC"
BN"6"30;
%"TAP"
"1","(2650,3725)","0","standard","I34";
;
CDS_LIB"standard"
BODY_TYPE"PLUMBING"
HDL_TAP"TRUE";
"B \NAC \NWC"1;
"S \NAC"
BN"5"31;
%"TAP"
"1","(2650,3675)","0","standard","I35";
;
CDS_LIB"standard"
BODY_TYPE"PLUMBING"
HDL_TAP"TRUE";
"B \NAC \NWC"1;
"S \NAC"
BN"4"32;
%"TAP"
"1","(2650,3825)","0","standard","I36";
;
CDS_LIB"standard"
BODY_TYPE"PLUMBING"
HDL_TAP"TRUE";
"B \NAC \NWC"1;
"S \NAC"
BN"7"29;
%"TAP"
"1","(-725,3125)","2","standard","I4";
;
CDS_LIB"standard"
BODY_TYPE"PLUMBING"
HDL_TAP"TRUE";
"B \NAC \NWC"4;
"S \NAC"
BN"2"10;
%"TAP"
"1","(-725,3075)","2","standard","I5";
;
CDS_LIB"standard"
BODY_TYPE"PLUMBING"
HDL_TAP"TRUE";
"B \NAC \NWC"4;
"S \NAC"
BN"1"11;
%"TAP"
"1","(-725,3025)","2","standard","I6";
;
CDS_LIB"standard"
BODY_TYPE"PLUMBING"
HDL_TAP"TRUE";
"B \NAC \NWC"4;
"S \NAC"
BN"0"12;
%"TAP"
"1","(-725,3175)","2","standard","I7";
;
CDS_LIB"standard"
BODY_TYPE"PLUMBING"
HDL_TAP"TRUE";
"B \NAC \NWC"4;
"S \NAC"
BN"3"9;
%"TAP"
"1","(-725,3225)","2","standard","I8";
;
CDS_LIB"standard"
BODY_TYPE"PLUMBING"
HDL_TAP"TRUE";
"B \NAC \NWC"4;
"S \NAC"
BN"4"8;
%"TAP"
"1","(-725,3375)","2","standard","I9";
;
CDS_LIB"standard"
BODY_TYPE"PLUMBING"
HDL_TAP"TRUE";
"B \NAC \NWC"4;
"S \NAC"
BN"7"5;
END.
